# TIMECARD (Time Appliance Project (Time Card)) — schematic netlist excerpt (pin names and nets, part order shuffled) for the footprints in the layout excerpt that follows; sources: Cadence DE-HDL packaged netlist, KiCad conversion of R4006-B0001-02_R01.brd

J9  CONN_HDR_2X2_M_S_SMT  pkg S_M_H_2X2_S_P100_V3  page 16
  \1\  = UNNAMED_5_CONNHDR2X2MSSMT_I126_
  \2\  = EEPROM_SDA
  \3\  = UNNAMED_5_CONNHDR2X2MSSMT_I12_1
  \4\  = EEPROM_SCL

C83  CAPACITOR  0.1UF 10V 10%  pkg SMC_0402R_H022  page 23 : \1\ = XP3R3V_FPGA ; \2\ = SG

(kicad_pcb
	(version 20260206)
	(generator "pcbnew")
	(generator_version "10.0")
	(general
		(thickness 1.6)
		(legacy_teardrops no)
	)
	(paper "A4")
	(title_block
		(title "timecard-production-celestica-r4006 — R4006-B0001-02_R01.brd")
		(comment 1 "Time Appliance Project (Time Card) / footprints 332-333 of 1113")
	)
	(layers
		(0 "F.Cu" signal "TOP")
		(4 "In1.Cu" signal "L02_GND1")
		(6 "In2.Cu" signal "L03_SIG1")
		(8 "In3.Cu" signal "L04_GND2")
		(10 "In4.Cu" signal "L05_VCC1")
		(12 "In5.Cu" signal "L06_VCC2")
		(14 "In6.Cu" signal "L07_GND3")
		(16 "In7.Cu" signal "L08_SIG2")
		(18 "In8.Cu" signal "L09_GND4")
		(2 "B.Cu" signal "BOTTOM")
		(9 "F.Adhes" user "F.Adhesive")
		(11 "B.Adhes" user "B.Adhesive")
		(13 "F.Paste" user "Package Geometry/Pastemask Top")
		(15 "B.Paste" user "Package Geometry/Pastemask Bottom")
		(5 "F.SilkS" user "Ref Des/Silkscreen Top")
		(7 "B.SilkS" user "Ref Des/Silkscreen Bottom")
		(1 "F.Mask" user "Board Geometry/Soldermask Top")
		(3 "B.Mask" user "Board Geometry/Soldermask Bottom")
		(17 "Dwgs.User" user "User.Drawings")
		(19 "Cmts.User" user "User.Comments")
		(21 "Eco1.User" user "User.Eco1")
		(23 "Eco2.User" user "User.Eco2")
		(25 "Edge.Cuts" user "Board Geometry/Outline")
		(27 "Margin" user)
		(31 "F.CrtYd" user "Package Geometry/Place Bound Top")
		(29 "B.CrtYd" user "Package Geometry/Place Bound Bottom")
		(35 "F.Fab" user "Ref Des/Assembly Top")
		(33 "B.Fab" user "Ref Des/Assembly Bottom")
	)
	(footprint ""
		(layer "F.Cu")
		(at 19.177 -38.735 180)
		(property "Reference" "J9"
			(at -3.556 1.61163 0)
			(unlocked yes)
			(layer "F.SilkS")
			(effects
				(font
					(size 0.7874 0.5842)
					(thickness 0.1524)
				)
			)
		)
		(property "Value" ""
			(at 0 0 180)
			(layer "F.Fab")
			(effects
				(font
					(size 1.27 1.27)
				)
			)
		)
		(property "User Part Number" "PARTNUM*"
			(at 0.069088 7.712456 180)
			(unlocked yes)
			(layer "Cmts.User")
			(hide yes)
			(effects
				(font
					(size 0.7874 0.5842)
					(thickness 0.000001)
				)
			)
		)
		(property "Device Type" "CONN_HDR_2X2_M_S_SMT-G200-1068A"
			(at 0.069088 6.518656 180)
			(unlocked yes)
			(layer "F.Fab")
			(hide yes)
			(effects
				(font
					(size 0.7874 0.5842)
					(thickness 0.000001)
				)
			)
		)
		(duplicate_pad_numbers_are_jumpers no)
		(fp_line
			(start 2.589022 4.637024)
			(end -2.589022 4.637024)
			(stroke
				(width 0.1)
				(type default)
			)
			(layer "F.SilkS")
		)
		(fp_line
			(start 2.589022 -4.637024)
			(end 2.589022 4.637024)
			(stroke
				(width 0.1)
				(type default)
			)
			(layer "F.SilkS")
		)
		(fp_line
			(start -2.589022 4.637024)
			(end -2.589022 -4.637024)
			(stroke
				(width 0.1)
				(type default)
			)
			(layer "F.SilkS")
		)
		(fp_line
			(start -2.589022 -4.637024)
			(end 2.589022 -4.637024)
			(stroke
				(width 0.1)
				(type default)
			)
			(layer "F.SilkS")
		)
		(fp_rect
			(start -2.843022 4.891024)
			(end 2.843022 -4.891024)
			(stroke
				(width 0)
				(type default)
			)
			(fill no)
			(layer "F.CrtYd")
		)
		(fp_line
			(start 2.335022 2.439924)
			(end 2.335022 -2.439924)
			(stroke
				(width 0.1)
				(type default)
			)
			(layer "F.Fab")
		)
		(fp_line
			(start 2.335022 -2.439924)
			(end -2.335022 -2.439924)
			(stroke
				(width 0.1)
				(type default)
			)
			(layer "F.Fab")
		)
		(fp_line
			(start -2.335022 2.439924)
			(end 2.335022 2.439924)
			(stroke
				(width 0.1)
				(type default)
			)
			(layer "F.Fab")
		)
		(fp_line
			(start -2.335022 -2.439924)
			(end -2.335022 2.439924)
			(stroke
				(width 0.1)
				(type default)
			)
			(layer "F.Fab")
		)
		(fp_text user "3"
			(at 1.8161 5.29463 0)
			(unlocked yes)
			(layer "F.SilkS")
			(effects
				(font
					(size 0.7874 0.5842)
					(thickness 0.1524)
				)
				(justify left)
			)
		)
		(fp_text user "4"
			(at 1.3081 -5.24637 0)
			(unlocked yes)
			(layer "F.SilkS")
			(effects
				(font
					(size 0.7874 0.5842)
					(thickness 0.1524)
				)
				(justify left)
			)
		)
		(fp_text user "1"
			(at -2.6289 4.27863 0)
			(unlocked yes)
			(layer "F.SilkS")
			(effects
				(font
					(size 0.7874 0.5842)
					(thickness 0.1524)
				)
				(justify left)
			)
		)
		(fp_text user "2"
			(at -2.8829 -3.34137 0)
			(unlocked yes)
			(layer "F.SilkS")
			(effects
				(font
					(size 0.7874 0.5842)
					(thickness 0.1524)
				)
				(justify left)
			)
		)
		(fp_text user "4"
			(at 1.770888 -3.285744 0)
			(unlocked yes)
			(layer "F.Fab")
			(effects
				(font
					(size 0.7874 0.5842)
					(thickness 0.1524)
				)
				(justify left)
			)
		)
		(fp_text user "3"
			(at 1.41478 3.674872 0)
			(unlocked yes)
			(layer "F.Fab")
			(effects
				(font
					(size 0.7874 0.5842)
					(thickness 0.1524)
				)
				(justify left)
			)
		)
		(fp_text user "2"
			(at -1.005332 -3.25247 0)
			(unlocked yes)
			(layer "F.Fab")
			(effects
				(font
					(size 0.7874 0.5842)
					(thickness 0.1524)
				)
				(justify left)
			)
		)
		(fp_text user "1"
			(at -1.22682 3.674872 0)
			(unlocked yes)
			(layer "F.Fab")
			(effects
				(font
					(size 0.7874 0.5842)
					(thickness 0.1524)
				)
				(justify left)
			)
		)
		(pad "1" smd rect
			(at -1.27 2.605024 180)
			(size 1.27 3.556)
			(layers "F.Cu" "F.Mask" "F.Paste")
			(net "UNNAMED_5_CONNHDR2X2MSSMT_I126_")
		)
		(pad "2" smd rect
			(at -1.27 -2.605024 180)
			(size 1.27 3.556)
			(layers "F.Cu" "F.Mask" "F.Paste")
			(net "EEPROM_SDA")
		)
		(pad "3" smd rect
			(at 1.27 2.605024 180)
			(size 1.27 3.556)
			(layers "F.Cu" "F.Mask" "F.Paste")
			(net "UNNAMED_5_CONNHDR2X2MSSMT_I12_1")
		)
		(pad "4" smd rect
			(at 1.27 -2.605024 180)
			(size 1.27 3.556)
			(layers "F.Cu" "F.Mask" "F.Paste")
			(net "EEPROM_SCL")
		)
	)
	(footprint ""
		(layer "F.Cu")
		(at 15.875 -28.067 -90)
		(property "Reference" "C83"
			(at 0.127 -1.81737 90)
			(unlocked yes)
			(layer "F.SilkS")
			(effects
				(font
					(size 0.7874 0.5842)
					(thickness 0.1524)
				)
			)
		)
		(property "Value" "VAL*"
			(at 0.0762 2.067306 270)
			(unlocked yes)
			(layer "F.Fab")
			(hide yes)
			(effects
				(font
					(size 0.7874 0.5842)
					(thickness 0.1524)
				)
			)
		)
		(property "Device Type" "CAPACITOR-G105-0B104-CK,0.1UF,A"
			(at 0.0508 1.127506 270)
			(unlocked yes)
			(layer "F.Fab")
			(hide yes)
			(effects
				(font
					(size 0.7874 0.5842)
					(thickness 0.1524)
				)
			)
		)
		(property "User Part Number" "PARTNUM*"
			(at 0.1016 4.023106 270)
			(unlocked yes)
			(layer "Cmts.User")
			(hide yes)
			(effects
				(font
					(size 0.7874 0.5842)
					(thickness 0.1524)
				)
			)
		)
		(property "Tolerance" "TOL*"
			(at 0.0762 3.032506 270)
			(unlocked yes)
			(layer "Cmts.User")
			(hide yes)
			(effects
				(font
					(size 0.7874 0.5842)
					(thickness 0.1524)
				)
			)
		)
		(duplicate_pad_numbers_are_jumpers no)
		(fp_line
			(start -1.143 0.5588)
			(end 1.143 0.5588)
			(stroke
				(width 0.1)
				(type default)
			)
			(layer "F.SilkS")
		)
		(fp_line
			(start 1.143 0.5588)
			(end 1.143 -0.5588)
			(stroke
				(width 0.1)
				(type default)
			)
			(layer "F.SilkS")
		)
		(fp_line
			(start -1.143 -0.5588)
			(end -1.143 0.5588)
			(stroke
				(width 0.1)
				(type default)
			)
			(layer "F.SilkS")
		)
		(fp_line
			(start 1.143 -0.5588)
			(end -1.143 -0.5588)
			(stroke
				(width 0.1)
				(type default)
			)
			(layer "F.SilkS")
		)
		(fp_rect
			(start -1.143 -0.5588)
			(end 1.143 0.5588)
			(stroke
				(width 0)
				(type default)
			)
			(fill no)
			(layer "F.CrtYd")
		)
		(fp_line
			(start -0.508 0.3048)
			(end 0.508 0.3048)
			(stroke
				(width 0.1)
				(type default)
			)
			(layer "F.Fab")
		)
		(fp_line
			(start 0.508 0.3048)
			(end 0.508 -0.3048)
			(stroke
				(width 0.1)
				(type default)
			)
			(layer "F.Fab")
		)
		(fp_line
			(start -0.508 -0.3048)
			(end -0.508 0.3048)
			(stroke
				(width 0.1)
				(type default)
			)
			(layer "F.Fab")
		)
		(fp_line
			(start 0.508 -0.3048)
			(end -0.508 -0.3048)
			(stroke
				(width 0.1)
				(type default)
			)
			(layer "F.Fab")
		)
		(pad "1" smd rect
			(at -0.5334 0 270)
			(size 0.7112 0.6096)
			(layers "F.Cu" "F.Mask" "F.Paste")
			(net "XP3R3V_FPGA")
		)
		(pad "2" smd rect
			(at 0.5334 0 270)
			(size 0.7112 0.6096)
			(layers "F.Cu" "F.Mask" "F.Paste")
			(net "SG")
		)
		(zone
			(layer "F.Cu")
			(hatch none 0.5)
			(connect_pads
				(clearance 0)
			)
			(min_thickness 0.25)
			(keepout
				(tracks allowed)
				(vias not_allowed)
				(pads allowed)
				(copperpour not_allowed)
				(footprints allowed)
			)
			(placement
				(enabled no)
				(sheetname "")
			)
			(fill
				(thermal_gap 0.5)
				(thermal_bridge_width 0.5)
				(island_removal_mode 0)
			)
			(polygon
				(pts
					(xy 16.1798 -28.1432) (xy 15.5702 -28.1432) (xy 15.5702 -27.9908) (xy 16.1798 -27.9908)
				)
			)
		)
	)
)
